(kicad_pcb
	(version 20260206)
	(generator "pcbnew")
	(generator_version "10.0")
	(general
		(thickness 1.6)
		(legacy_teardrops no)
	)
	(paper "A4")
	(title_block
		(title "Wiwynn_Tioga_Pass_MB.brd")
		(comment 1 "Tioga Pass / footprint 3114 of 4770 (J9U1), pads 124-243 of 291")
	)
	(layers
		(0 "F.Cu" signal "TOP")
		(4 "In1.Cu" signal "L2GND")
		(6 "In2.Cu" signal "L3")
		(8 "In3.Cu" signal "L4GND")
		(10 "In4.Cu" signal "L5")
		(12 "In5.Cu" signal "L6GND")
		(14 "In6.Cu" signal "L7VCC")
		(16 "In7.Cu" signal "L8VCC")
		(18 "In8.Cu" signal "L9GND")
		(20 "In9.Cu" signal "L10")
		(22 "In10.Cu" signal "L11GND")
		(24 "In11.Cu" signal "L12")
		(26 "In12.Cu" signal "L13GND")
		(2 "B.Cu" signal "BOTTOM")
		(9 "F.Adhes" user "F.Adhesive")
		(11 "B.Adhes" user "B.Adhesive")
		(13 "F.Paste" user "Package Geometry/Pastemask Top")
		(15 "B.Paste" user "Package Geometry/Pastemask Bottom")
		(5 "F.SilkS" user "Ref Des/Silkscreen Top")
		(7 "B.SilkS" user "Ref Des/Silkscreen Bottom")
		(1 "F.Mask" user "Board Geometry/Soldermask Top")
		(3 "B.Mask" user "Board Geometry/Soldermask Bottom")
		(17 "Dwgs.User" user "User.Drawings")
		(19 "Cmts.User" user "User.Comments")
		(21 "Eco1.User" user "User.Eco1")
		(23 "Eco2.User" user "User.Eco2")
		(25 "Edge.Cuts" user "Board Geometry/Outline")
		(27 "Margin" user)
		(31 "F.CrtYd" user "Package Geometry/Place Bound Top")
		(29 "B.CrtYd" user "Package Geometry/Place Bound Bottom")
		(35 "F.Fab" user "Ref Des/Assembly Top")
		(33 "B.Fab" user "Ref Des/Assembly Bottom")
	)
	(footprint ""
		(layer "B.Cu")
		(at 29.699458 -15.222982 90)
		(property "Reference" "J9U1"
			(at 2.276348 37.991542 0)
			(unlocked yes)
			(layer "B.SilkS")
			(effects
				(font
					(size 0.7874 0.5842)
					(thickness 0.1524)
				)
				(justify left mirror)
			)
		)
		(property "Value" ""
			(at 0 0 90)
			(layer "B.Fab")
			(effects
				(font
					(size 1.27 1.27)
				)
				(justify mirror)
			)
		)
		(duplicate_pad_numbers_are_jumpers no)
		(pad "121" smd rect
			(at 0 107.100116 270)
			(size 1.8034 0.508)
			(layers "B.Cu" "B.Mask" "B.Paste")
			(net "M_H_DQS_DP<15>")
		)
		(pad "122" smd rect
			(at 0 107.95 270)
			(size 1.8034 0.508)
			(layers "B.Cu" "B.Mask" "B.Paste")
			(net "M_H_DQS_DN<15>")
		)
		(pad "123" smd rect
			(at 0 108.799884 270)
			(size 1.8034 0.508)
			(layers "B.Cu" "B.Mask" "B.Paste")
			(net "GND")
		)
		(pad "124" smd rect
			(at 0 109.650022 270)
			(size 1.8034 0.508)
			(layers "B.Cu" "B.Mask" "B.Paste")
			(net "M_H_DQ<54>")
		)
		(pad "125" smd rect
			(at 0 110.499906 270)
			(size 1.8034 0.508)
			(layers "B.Cu" "B.Mask" "B.Paste")
			(net "GND")
		)
		(pad "126" smd rect
			(at 0 111.350044 270)
			(size 1.8034 0.508)
			(layers "B.Cu" "B.Mask" "B.Paste")
			(net "M_H_DQ<50>")
		)
		(pad "127" smd rect
			(at 0 112.199928 270)
			(size 1.8034 0.508)
			(layers "B.Cu" "B.Mask" "B.Paste")
			(net "GND")
		)
		(pad "128" smd rect
			(at 0 113.050066 270)
			(size 1.8034 0.508)
			(layers "B.Cu" "B.Mask" "B.Paste")
			(net "M_H_DQ<60>")
		)
		(pad "129" smd rect
			(at 0 113.89995 270)
			(size 1.8034 0.508)
			(layers "B.Cu" "B.Mask" "B.Paste")
			(net "GND")
		)
		(pad "130" smd rect
			(at 0 114.750088 270)
			(size 1.8034 0.508)
			(layers "B.Cu" "B.Mask" "B.Paste")
			(net "M_H_DQ<56>")
		)
		(pad "131" smd rect
			(at 0 115.599972 270)
			(size 1.8034 0.508)
			(layers "B.Cu" "B.Mask" "B.Paste")
			(net "GND")
		)
		(pad "132" smd rect
			(at 0 116.45011 270)
			(size 1.8034 0.508)
			(layers "B.Cu" "B.Mask" "B.Paste")
			(net "M_H_DQS_DP<16>")
		)
		(pad "133" smd rect
			(at 0 117.299994 270)
			(size 1.8034 0.508)
			(layers "B.Cu" "B.Mask" "B.Paste")
			(net "M_H_DQS_DN<16>")
		)
		(pad "134" smd rect
			(at 0 118.149878 270)
			(size 1.8034 0.508)
			(layers "B.Cu" "B.Mask" "B.Paste")
			(net "GND")
		)
		(pad "135" smd rect
			(at 0 119.000016 270)
			(size 1.8034 0.508)
			(layers "B.Cu" "B.Mask" "B.Paste")
			(net "M_H_DQ<62>")
		)
		(pad "136" smd rect
			(at 0 119.8499 270)
			(size 1.8034 0.508)
			(layers "B.Cu" "B.Mask" "B.Paste")
			(net "GND")
		)
		(pad "137" smd rect
			(at 0 120.700038 270)
			(size 1.8034 0.508)
			(layers "B.Cu" "B.Mask" "B.Paste")
			(net "M_H_DQ<58>")
		)
		(pad "138" smd rect
			(at 0 121.549922 270)
			(size 1.8034 0.508)
			(layers "B.Cu" "B.Mask" "B.Paste")
			(net "GND")
		)
		(pad "139" smd rect
			(at 0 122.40006 270)
			(size 1.8034 0.508)
			(layers "B.Cu" "B.Mask" "B.Paste")
			(net "PVPP_GHJ")
		)
		(pad "140" smd rect
			(at 0 123.249944 270)
			(size 1.8034 0.508)
			(layers "B.Cu" "B.Mask" "B.Paste")
			(net "PVPP_GHJ")
		)
		(pad "141" smd rect
			(at 0 124.100082 270)
			(size 1.8034 0.508)
			(layers "B.Cu" "B.Mask" "B.Paste")
			(net "SMB_DDR_GHJ_VPP_SCL")
		)
		(pad "142" smd rect
			(at 0 124.949966 270)
			(size 1.8034 0.508)
			(layers "B.Cu" "B.Mask" "B.Paste")
			(net "PVPP_GHJ")
		)
		(pad "143" smd rect
			(at 0 125.800104 270)
			(size 1.8034 0.508)
			(layers "B.Cu" "B.Mask" "B.Paste")
			(net "PVPP_GHJ")
		)
		(pad "144" smd rect
			(at 0 126.649988 270)
			(size 1.8034 0.508)
			(layers "B.Cu" "B.Mask" "B.Paste")
			(net "TP_CH_H_DIMM0_RFU_2")
		)
		(pad "145" smd rect
			(at -4.59994 0 270)
			(size 1.8034 0.508)
			(layers "B.Cu" "B.Mask" "B.Paste")
			(net "P12V_NVDIMM_GHJ")
		)
		(pad "146" smd rect
			(at -4.59994 0.849884 270)
			(size 1.8034 0.508)
			(layers "B.Cu" "B.Mask" "B.Paste")
			(net "M_H_VREF")
		)
		(pad "147" smd rect
			(at -4.59994 1.700022 270)
			(size 1.8034 0.508)
			(layers "B.Cu" "B.Mask" "B.Paste")
			(net "GND")
		)
		(pad "148" smd rect
			(at -4.59994 2.549906 270)
			(size 1.8034 0.508)
			(layers "B.Cu" "B.Mask" "B.Paste")
			(net "M_H_DQ<5>")
		)
		(pad "149" smd rect
			(at -4.59994 3.400044 270)
			(size 1.8034 0.508)
			(layers "B.Cu" "B.Mask" "B.Paste")
			(net "GND")
		)
		(pad "150" smd rect
			(at -4.59994 4.249928 270)
			(size 1.8034 0.508)
			(layers "B.Cu" "B.Mask" "B.Paste")
			(net "M_H_DQ<1>")
		)
		(pad "151" smd rect
			(at -4.59994 5.100066 270)
			(size 1.8034 0.508)
			(layers "B.Cu" "B.Mask" "B.Paste")
			(net "GND")
		)
		(pad "152" smd rect
			(at -4.59994 5.94995 270)
			(size 1.8034 0.508)
			(layers "B.Cu" "B.Mask" "B.Paste")
			(net "M_H_DQS_DN<0>")
		)
		(pad "153" smd rect
			(at -4.59994 6.800088 270)
			(size 1.8034 0.508)
			(layers "B.Cu" "B.Mask" "B.Paste")
			(net "M_H_DQS_DP<0>")
		)
		(pad "154" smd rect
			(at -4.59994 7.649972 270)
			(size 1.8034 0.508)
			(layers "B.Cu" "B.Mask" "B.Paste")
			(net "GND")
		)
		(pad "155" smd rect
			(at -4.59994 8.50011 270)
			(size 1.8034 0.508)
			(layers "B.Cu" "B.Mask" "B.Paste")
			(net "M_H_DQ<7>")
		)
		(pad "156" smd rect
			(at -4.59994 9.349994 270)
			(size 1.8034 0.508)
			(layers "B.Cu" "B.Mask" "B.Paste")
			(net "GND")
		)
		(pad "157" smd rect
			(at -4.59994 10.199878 270)
			(size 1.8034 0.508)
			(layers "B.Cu" "B.Mask" "B.Paste")
			(net "M_H_DQ<3>")
		)
		(pad "158" smd rect
			(at -4.59994 11.050016 270)
			(size 1.8034 0.508)
			(layers "B.Cu" "B.Mask" "B.Paste")
			(net "GND")
		)
		(pad "159" smd rect
			(at -4.59994 11.8999 270)
			(size 1.8034 0.508)
			(layers "B.Cu" "B.Mask" "B.Paste")
			(net "M_H_DQ<13>")
		)
		(pad "160" smd rect
			(at -4.59994 12.750038 270)
			(size 1.8034 0.508)
			(layers "B.Cu" "B.Mask" "B.Paste")
			(net "GND")
		)
		(pad "161" smd rect
			(at -4.59994 13.599922 270)
			(size 1.8034 0.508)
			(layers "B.Cu" "B.Mask" "B.Paste")
			(net "M_H_DQ<9>")
		)
		(pad "162" smd rect
			(at -4.59994 14.45006 270)
			(size 1.8034 0.508)
			(layers "B.Cu" "B.Mask" "B.Paste")
			(net "GND")
		)
		(pad "163" smd rect
			(at -4.59994 15.299944 270)
			(size 1.8034 0.508)
			(layers "B.Cu" "B.Mask" "B.Paste")
			(net "M_H_DQS_DN<1>")
		)
		(pad "164" smd rect
			(at -4.59994 16.150082 270)
			(size 1.8034 0.508)
			(layers "B.Cu" "B.Mask" "B.Paste")
			(net "M_H_DQS_DP<1>")
		)
		(pad "165" smd rect
			(at -4.59994 16.999966 270)
			(size 1.8034 0.508)
			(layers "B.Cu" "B.Mask" "B.Paste")
			(net "GND")
		)
		(pad "166" smd rect
			(at -4.59994 17.850104 270)
			(size 1.8034 0.508)
			(layers "B.Cu" "B.Mask" "B.Paste")
			(net "M_H_DQ<15>")
		)
		(pad "167" smd rect
			(at -4.59994 18.699988 270)
			(size 1.8034 0.508)
			(layers "B.Cu" "B.Mask" "B.Paste")
			(net "GND")
		)
		(pad "168" smd rect
			(at -4.59994 19.550126 270)
			(size 1.8034 0.508)
			(layers "B.Cu" "B.Mask" "B.Paste")
			(net "M_H_DQ<11>")
		)
		(pad "169" smd rect
			(at -4.59994 20.40001 270)
			(size 1.8034 0.508)
			(layers "B.Cu" "B.Mask" "B.Paste")
			(net "GND")
		)
		(pad "170" smd rect
			(at -4.59994 21.249894 270)
			(size 1.8034 0.508)
			(layers "B.Cu" "B.Mask" "B.Paste")
			(net "M_H_DQ<21>")
		)
		(pad "171" smd rect
			(at -4.59994 22.100032 270)
			(size 1.8034 0.508)
			(layers "B.Cu" "B.Mask" "B.Paste")
			(net "GND")
		)
		(pad "172" smd rect
			(at -4.59994 22.949916 270)
			(size 1.8034 0.508)
			(layers "B.Cu" "B.Mask" "B.Paste")
			(net "M_H_DQ<17>")
		)
		(pad "173" smd rect
			(at -4.59994 23.800054 270)
			(size 1.8034 0.508)
			(layers "B.Cu" "B.Mask" "B.Paste")
			(net "GND")
		)
		(pad "174" smd rect
			(at -4.59994 24.649938 270)
			(size 1.8034 0.508)
			(layers "B.Cu" "B.Mask" "B.Paste")
			(net "M_H_DQS_DN<2>")
		)
		(pad "175" smd rect
			(at -4.59994 25.500076 270)
			(size 1.8034 0.508)
			(layers "B.Cu" "B.Mask" "B.Paste")
			(net "M_H_DQS_DP<2>")
		)
		(pad "176" smd rect
			(at -4.59994 26.34996 270)
			(size 1.8034 0.508)
			(layers "B.Cu" "B.Mask" "B.Paste")
			(net "GND")
		)
		(pad "177" smd rect
			(at -4.59994 27.200098 270)
			(size 1.8034 0.508)
			(layers "B.Cu" "B.Mask" "B.Paste")
			(net "M_H_DQ<23>")
		)
		(pad "178" smd rect
			(at -4.59994 28.049982 270)
			(size 1.8034 0.508)
			(layers "B.Cu" "B.Mask" "B.Paste")
			(net "GND")
		)
		(pad "179" smd rect
			(at -4.59994 28.90012 270)
			(size 1.8034 0.508)
			(layers "B.Cu" "B.Mask" "B.Paste")
			(net "M_H_DQ<19>")
		)
		(pad "180" smd rect
			(at -4.59994 29.750004 270)
			(size 1.8034 0.508)
			(layers "B.Cu" "B.Mask" "B.Paste")
			(net "GND")
		)
		(pad "181" smd rect
			(at -4.59994 30.599888 270)
			(size 1.8034 0.508)
			(layers "B.Cu" "B.Mask" "B.Paste")
			(net "M_H_DQ<29>")
		)
		(pad "182" smd rect
			(at -4.59994 31.450026 270)
			(size 1.8034 0.508)
			(layers "B.Cu" "B.Mask" "B.Paste")
			(net "GND")
		)
		(pad "183" smd rect
			(at -4.59994 32.29991 270)
			(size 1.8034 0.508)
			(layers "B.Cu" "B.Mask" "B.Paste")
			(net "M_H_DQ<25>")
		)
		(pad "184" smd rect
			(at -4.59994 33.150048 270)
			(size 1.8034 0.508)
			(layers "B.Cu" "B.Mask" "B.Paste")
			(net "GND")
		)
		(pad "185" smd rect
			(at -4.59994 33.999932 270)
			(size 1.8034 0.508)
			(layers "B.Cu" "B.Mask" "B.Paste")
			(net "M_H_DQS_DN<3>")
		)
		(pad "186" smd rect
			(at -4.59994 34.85007 270)
			(size 1.8034 0.508)
			(layers "B.Cu" "B.Mask" "B.Paste")
			(net "M_H_DQS_DP<3>")
		)
		(pad "187" smd rect
			(at -4.59994 35.699954 270)
			(size 1.8034 0.508)
			(layers "B.Cu" "B.Mask" "B.Paste")
			(net "GND")
		)
		(pad "188" smd rect
			(at -4.59994 36.550092 270)
			(size 1.8034 0.508)
			(layers "B.Cu" "B.Mask" "B.Paste")
			(net "M_H_DQ<31>")
		)
		(pad "189" smd rect
			(at -4.59994 37.399976 270)
			(size 1.8034 0.508)
			(layers "B.Cu" "B.Mask" "B.Paste")
			(net "GND")
		)
		(pad "190" smd rect
			(at -4.59994 38.250114 270)
			(size 1.8034 0.508)
			(layers "B.Cu" "B.Mask" "B.Paste")
			(net "M_H_DQ<27>")
		)
		(pad "191" smd rect
			(at -4.59994 39.099998 270)
			(size 1.8034 0.508)
			(layers "B.Cu" "B.Mask" "B.Paste")
			(net "GND")
		)
		(pad "192" smd rect
			(at -4.59994 39.949882 270)
			(size 1.8034 0.508)
			(layers "B.Cu" "B.Mask" "B.Paste")
			(net "M_H_ECC<5>")
		)
		(pad "193" smd rect
			(at -4.59994 40.80002 270)
			(size 1.8034 0.508)
			(layers "B.Cu" "B.Mask" "B.Paste")
			(net "GND")
		)
		(pad "194" smd rect
			(at -4.59994 41.649904 270)
			(size 1.8034 0.508)
			(layers "B.Cu" "B.Mask" "B.Paste")
			(net "M_H_ECC<1>")
		)
		(pad "195" smd rect
			(at -4.59994 42.500042 270)
			(size 1.8034 0.508)
			(layers "B.Cu" "B.Mask" "B.Paste")
			(net "GND")
		)
		(pad "196" smd rect
			(at -4.59994 43.349926 270)
			(size 1.8034 0.508)
			(layers "B.Cu" "B.Mask" "B.Paste")
			(net "M_H_DQS_DN<8>")
		)
		(pad "197" smd rect
			(at -4.59994 44.200064 270)
			(size 1.8034 0.508)
			(layers "B.Cu" "B.Mask" "B.Paste")
			(net "M_H_DQS_DP<8>")
		)
		(pad "198" smd rect
			(at -4.59994 45.049948 270)
			(size 1.8034 0.508)
			(layers "B.Cu" "B.Mask" "B.Paste")
			(net "GND")
		)
		(pad "199" smd rect
			(at -4.59994 45.900086 270)
			(size 1.8034 0.508)
			(layers "B.Cu" "B.Mask" "B.Paste")
			(net "M_H_ECC<7>")
		)
		(pad "200" smd rect
			(at -4.59994 46.74997 270)
			(size 1.8034 0.508)
			(layers "B.Cu" "B.Mask" "B.Paste")
			(net "GND")
		)
		(pad "201" smd rect
			(at -4.59994 47.600108 270)
			(size 1.8034 0.508)
			(layers "B.Cu" "B.Mask" "B.Paste")
			(net "M_H_ECC<3>")
		)
		(pad "202" smd rect
			(at -4.59994 48.449992 270)
			(size 1.8034 0.508)
			(layers "B.Cu" "B.Mask" "B.Paste")
			(net "GND")
		)
		(pad "203" smd rect
			(at -4.59994 49.299876 270)
			(size 1.8034 0.508)
			(layers "B.Cu" "B.Mask" "B.Paste")
			(net "M_H_CKE<3>")
		)
		(pad "204" smd rect
			(at -4.59994 50.150014 270)
			(size 1.8034 0.508)
			(layers "B.Cu" "B.Mask" "B.Paste")
			(net "PVDDQ_GHJ")
		)
		(pad "205" smd rect
			(at -4.59994 50.999898 270)
			(size 1.8034 0.508)
			(layers "B.Cu" "B.Mask" "B.Paste")
			(net "TP_CH_H_DIMM0_RFU_0")
		)
		(pad "206" smd rect
			(at -4.59994 51.850036 270)
			(size 1.8034 0.508)
			(layers "B.Cu" "B.Mask" "B.Paste")
			(net "PVDDQ_GHJ")
		)
		(pad "207" smd rect
			(at -4.59994 52.69992 270)
			(size 1.8034 0.508)
			(layers "B.Cu" "B.Mask" "B.Paste")
			(net "M_H_BG<1>")
		)
		(pad "208" smd rect
			(at -4.59994 53.550058 270)
			(size 1.8034 0.508)
			(layers "B.Cu" "B.Mask" "B.Paste")
			(net "M_H_ALERT_N")
		)
		(pad "209" smd rect
			(at -4.59994 54.399942 270)
			(size 1.8034 0.508)
			(layers "B.Cu" "B.Mask" "B.Paste")
			(net "PVDDQ_GHJ")
		)
		(pad "210" smd rect
			(at -4.59994 55.25008 270)
			(size 1.8034 0.508)
			(layers "B.Cu" "B.Mask" "B.Paste")
			(net "M_H_MA<11>")
		)
		(pad "211" smd rect
			(at -4.59994 56.099964 270)
			(size 1.8034 0.508)
			(layers "B.Cu" "B.Mask" "B.Paste")
			(net "M_H_MA<7>")
		)
		(pad "212" smd rect
			(at -4.59994 56.950102 270)
			(size 1.8034 0.508)
			(layers "B.Cu" "B.Mask" "B.Paste")
			(net "PVDDQ_GHJ")
		)
		(pad "213" smd rect
			(at -4.59994 57.799986 270)
			(size 1.8034 0.508)
			(layers "B.Cu" "B.Mask" "B.Paste")
			(net "M_H_MA<5>")
		)
		(pad "214" smd rect
			(at -4.59994 58.650124 270)
			(size 1.8034 0.508)
			(layers "B.Cu" "B.Mask" "B.Paste")
			(net "M_H_MA<4>")
		)
		(pad "215" smd rect
			(at -4.59994 59.500008 270)
			(size 1.8034 0.508)
			(layers "B.Cu" "B.Mask" "B.Paste")
			(net "PVDDQ_GHJ")
		)
		(pad "216" smd rect
			(at -4.59994 60.349892 270)
			(size 1.8034 0.508)
			(layers "B.Cu" "B.Mask" "B.Paste")
			(net "M_H_MA<2>")
		)
		(pad "217" smd rect
			(at -4.59994 61.20003 270)
			(size 1.8034 0.508)
			(layers "B.Cu" "B.Mask" "B.Paste")
			(net "PVDDQ_GHJ")
		)
		(pad "218" smd rect
			(at -4.59994 62.049914 270)
			(size 1.8034 0.508)
			(layers "B.Cu" "B.Mask" "B.Paste")
			(net "M_H_CLK_DP<3>")
		)
		(pad "219" smd rect
			(at -4.59994 62.900052 270)
			(size 1.8034 0.508)
			(layers "B.Cu" "B.Mask" "B.Paste")
			(net "M_H_CLK_DN<3>")
		)
		(pad "220" smd rect
			(at -4.59994 63.749936 270)
			(size 1.8034 0.508)
			(layers "B.Cu" "B.Mask" "B.Paste")
			(net "PVDDQ_GHJ")
		)
		(pad "221" smd rect
			(at -4.59994 64.600074 270)
			(size 1.8034 0.508)
			(layers "B.Cu" "B.Mask" "B.Paste")
			(net "PVTT_GHJ")
		)
		(pad "222" smd rect
			(at -4.59994 70.550024 270)
			(size 1.8034 0.508)
			(layers "B.Cu" "B.Mask" "B.Paste")
			(net "M_H_PAR")
		)
		(pad "223" smd rect
			(at -4.59994 71.399908 270)
			(size 1.8034 0.508)
			(layers "B.Cu" "B.Mask" "B.Paste")
			(net "PVDDQ_GHJ")
		)
		(pad "224" smd rect
			(at -4.59994 72.250046 270)
			(size 1.8034 0.508)
			(layers "B.Cu" "B.Mask" "B.Paste")
			(net "M_H_BA<1>")
		)
		(pad "225" smd rect
			(at -4.59994 73.09993 270)
			(size 1.8034 0.508)
			(layers "B.Cu" "B.Mask" "B.Paste")
			(net "M_H_MA<10>")
		)
		(pad "226" smd rect
			(at -4.59994 73.950068 270)
			(size 1.8034 0.508)
			(layers "B.Cu" "B.Mask" "B.Paste")
			(net "PVDDQ_GHJ")
		)
		(pad "227" smd rect
			(at -4.59994 74.799952 270)
			(size 1.8034 0.508)
			(layers "B.Cu" "B.Mask" "B.Paste")
			(net "TP_CH_H_DIMM0_RFU_1")
		)
		(pad "228" smd rect
			(at -4.59994 75.65009 270)
			(size 1.8034 0.508)
			(layers "B.Cu" "B.Mask" "B.Paste")
			(net "M_H_MA<14>")
		)
		(pad "229" smd rect
			(at -4.59994 76.499974 270)
			(size 1.8034 0.508)
			(layers "B.Cu" "B.Mask" "B.Paste")
			(net "PVDDQ_GHJ")
		)
		(pad "230" smd rect
			(at -4.59994 77.350112 270)
			(size 1.8034 0.508)
			(layers "B.Cu" "B.Mask" "B.Paste")
			(net "FM_ADR_COMPLETE_GHJ_N")
		)
		(pad "231" smd rect
			(at -4.59994 78.199996 270)
			(size 1.8034 0.508)
			(layers "B.Cu" "B.Mask" "B.Paste")
			(net "PVDDQ_GHJ")
		)
		(pad "232" smd rect
			(at -4.59994 79.04988 270)
			(size 1.8034 0.508)
			(layers "B.Cu" "B.Mask" "B.Paste")
			(net "M_H_MA<13>")
		)
		(pad "233" smd rect
			(at -4.59994 79.900018 270)
			(size 1.8034 0.508)
			(layers "B.Cu" "B.Mask" "B.Paste")
			(net "PVDDQ_GHJ")
		)
		(pad "234" smd rect
			(at -4.59994 80.749902 270)
			(size 1.8034 0.508)
			(layers "B.Cu" "B.Mask" "B.Paste")
			(net "M_H_MA<17>")
		)
		(pad "235" smd rect
			(at -4.59994 81.60004 270)
			(size 1.8034 0.508)
			(layers "B.Cu" "B.Mask" "B.Paste")
			(net "M_H_C<2>")
		)
		(pad "236" smd rect
			(at -4.59994 82.449924 270)
			(size 1.8034 0.508)
			(layers "B.Cu" "B.Mask" "B.Paste")
			(net "PVDDQ_GHJ")
		)
		(pad "237" smd rect
			(at -4.59994 83.300062 270)
			(size 1.8034 0.508)
			(layers "B.Cu" "B.Mask" "B.Paste")
			(net "M_H_CS_N<7>")
		)
		(pad "238" smd rect
			(at -4.59994 84.149946 270)
			(size 1.8034 0.508)
			(layers "B.Cu" "B.Mask" "B.Paste")
			(net "GND")
		)
		(pad "239" smd rect
			(at -4.59994 85.000084 270)
			(size 1.8034 0.508)
			(layers "B.Cu" "B.Mask" "B.Paste")
			(net "GND")
		)
		(pad "240" smd rect
			(at -4.59994 85.849968 270)
			(size 1.8034 0.508)
			(layers "B.Cu" "B.Mask" "B.Paste")
			(net "M_H_DQ<37>")
		)
	)
)
